# T6G (Grand Teton) — schematic netlist excerpt (pin names and nets, part order shuffled) for the footprints in the layout excerpt that follows; sources: Cadence DE-HDL packaged netlist, KiCad conversion of 04192023_DAF0TMB3IC0_F0TG_MB_C_brd_V02_OCP.brd

C992  Q_CAP  22UF 4V 20% X6S  pkg C0402  page 312 : A = P1V8_CPU0_RT_1D ; B = GND

X9002  TP_TDR_4P_FTS  TP_TDR_4P_DIP EMPTY  pkg TH  page 261
  S1  = TDR_DIFF_85_NECK_IN1_DP
  P1  = T1_GND
  P2  = T1_GND
  S2  = TDR_DIFF_85_NECK_IN1_DN

(kicad_pcb
	(version 20260206)
	(generator "pcbnew")
	(generator_version "10.0")
	(general
		(thickness 1.6)
		(legacy_teardrops no)
	)
	(paper "A4")
	(title_block
		(title "04192023_DAF0TMB3IC0_F0TG_MB_C_brd_V02_OCP.brd")
		(comment 1 "Grand Teton / footprints 3924-3925 of 8354")
	)
	(layers
		(0 "F.Cu" signal "TOP")
		(4 "In1.Cu" signal "GND")
		(6 "In2.Cu" signal "IN1")
		(8 "In3.Cu" signal "GND1")
		(10 "In4.Cu" signal "IN2")
		(12 "In5.Cu" signal "GND2")
		(14 "In6.Cu" signal "IN3")
		(16 "In7.Cu" signal "GND3")
		(18 "In8.Cu" signal "VCC")
		(20 "In9.Cu" signal "VCC1")
		(22 "In10.Cu" signal "GND4")
		(24 "In11.Cu" signal "IN4")
		(26 "In12.Cu" signal "GND5")
		(28 "In13.Cu" signal "IN5")
		(30 "In14.Cu" signal "GND6")
		(32 "In15.Cu" signal "IN6")
		(34 "In16.Cu" signal "GND7")
		(2 "B.Cu" signal "BOTTOM")
		(9 "F.Adhes" user "F.Adhesive")
		(11 "B.Adhes" user "B.Adhesive")
		(13 "F.Paste" user "Package Geometry/Pastemask Top")
		(15 "B.Paste" user "Package Geometry/Pastemask Bottom")
		(5 "F.SilkS" user "Ref Des/Silkscreen Top")
		(7 "B.SilkS" user "Ref Des/Silkscreen Bottom")
		(1 "F.Mask" user "Board Geometry/Soldermask Top")
		(3 "B.Mask" user "Board Geometry/Soldermask Bottom")
		(17 "Dwgs.User" user "User.Drawings")
		(19 "Cmts.User" user "User.Comments")
		(21 "Eco1.User" user "User.Eco1")
		(23 "Eco2.User" user "User.Eco2")
		(25 "Edge.Cuts" user "Board Geometry/Outline")
		(27 "Margin" user)
		(31 "F.CrtYd" user "Package Geometry/Place Bound Top")
		(29 "B.CrtYd" user "Package Geometry/Place Bound Bottom")
		(35 "F.Fab" user "Ref Des/Assembly Top")
		(33 "B.Fab" user "Ref Des/Assembly Bottom")
	)
	(footprint ""
		(layer "F.Cu")
		(at 506.185424 -306.9209 -90)
		(property "Reference" "X9002"
			(at -1.89738 4.962398 0)
			(unlocked yes)
			(layer "F.SilkS")
			(effects
				(font
					(size 0.7874 0.5842)
					(thickness 0.1524)
				)
				(justify left)
			)
		)
		(property "Value" ""
			(at 0 0 270)
			(layer "F.Fab")
			(effects
				(font
					(size 1.27 1.27)
				)
			)
		)
		(property "User Part Number" "N_A"
			(at 1.30175 1.27 0)
			(unlocked yes)
			(layer "Cmts.User")
			(hide yes)
			(effects
				(font
					(size 0.635 0.4064)
					(thickness 0.1524)
				)
			)
		)
		(property "Device Type" "TP_TDR_4P_FTS_TH-TP_TDR_4P_DIP,EMPTY,TP15"
			(at 1.30175 1.27 0)
			(unlocked yes)
			(layer "F.Fab")
			(hide yes)
			(effects
				(font
					(size 0.635 0.4064)
					(thickness 0.1524)
				)
			)
		)
		(duplicate_pad_numbers_are_jumpers no)
		(fp_line
			(start 0 3.81)
			(end 2.54 3.81)
			(stroke
				(width 0.1524)
				(type default)
			)
			(layer "F.SilkS")
		)
		(fp_line
			(start 2.54 3.81)
			(end 2.54 3.6703)
			(stroke
				(width 0.1524)
				(type default)
			)
			(layer "F.SilkS")
		)
		(fp_line
			(start 0 3.175)
			(end 0 3.81)
			(stroke
				(width 0.1524)
				(type default)
			)
			(layer "F.SilkS")
		)
		(fp_line
			(start 2.54 1.4097)
			(end 2.54 1.1303)
			(stroke
				(width 0.1524)
				(type default)
			)
			(layer "F.SilkS")
		)
		(fp_line
			(start 0 0.635)
			(end 0 1.905)
			(stroke
				(width 0.1524)
				(type default)
			)
			(layer "F.SilkS")
		)
		(fp_line
			(start 2.54 -1.1303)
			(end 2.54 -1.27)
			(stroke
				(width 0.1524)
				(type default)
			)
			(layer "F.SilkS")
		)
		(fp_line
			(start 0 -1.27)
			(end 0 -0.635)
			(stroke
				(width 0.1524)
				(type default)
			)
			(layer "F.SilkS")
		)
		(fp_line
			(start 2.54 -1.27)
			(end 0 -1.27)
			(stroke
				(width 0.1524)
				(type default)
			)
			(layer "F.SilkS")
		)
		(fp_poly
			(pts
				(xy -2.285746 -0.762) (xy -0.761746 0) (xy -2.285746 0.762)
			)
			(stroke
				(width 0)
				(type default)
			)
			(fill yes)
			(layer "F.SilkS")
		)
		(fp_line
			(start 0 3.81)
			(end 2.54 3.81)
			(stroke
				(width 0.1)
				(type default)
			)
			(layer "F.Fab")
		)
		(fp_line
			(start 2.54 3.81)
			(end 2.54 -1.27)
			(stroke
				(width 0.1)
				(type default)
			)
			(layer "F.Fab")
		)
		(fp_line
			(start 0 -1.27)
			(end 0 3.81)
			(stroke
				(width 0.1)
				(type default)
			)
			(layer "F.Fab")
		)
		(fp_line
			(start 2.54 -1.27)
			(end 0 -1.27)
			(stroke
				(width 0.1)
				(type default)
			)
			(layer "F.Fab")
		)
		(fp_poly
			(pts
				(xy -0.761746 0) (xy -2.285746 -0.762) (xy -2.285746 0.762)
			)
			(stroke
				(width 0)
				(type default)
			)
			(fill yes)
			(layer "F.Fab")
		)
		(pad "1" thru_hole circle
			(at 0 0 270)
			(size 1.0033 1.0033)
			(drill 0.249936)
			(layers "*.Cu" "*.Mask")
			(remove_unused_layers no)
			(net "TDR_DIFF_85_NECK_IN1_DP")
			(clearance 0.10795)
			(thermal_gap 0.10795)
			(padstack
				(mode front_inner_back)
				(layer "Inner"
					(shape circle)
					(size 0.8001 0.8001)
					(clearance 0.1524)
				)
				(layer "B.Cu"
					(shape circle)
					(size 1.0033 1.0033)
					(clearance 0.10795)
				)
			)
		)
		(pad "2" thru_hole circle
			(at 2.54 0 270)
			(size 1.9939 1.9939)
			(drill 0.249936)
			(layers "*.Cu" "*.Mask")
			(remove_unused_layers no)
			(net "T1_GND")
			(clearance 0.10795)
			(thermal_gap 0.10795)
			(padstack
				(mode front_inner_back)
				(layer "Inner"
					(shape circle)
					(size 0.8001 0.8001)
					(clearance 0.1524)
				)
				(layer "B.Cu"
					(shape circle)
					(size 1.9939 1.9939)
					(clearance 0.10795)
				)
			)
		)
		(pad "3" thru_hole circle
			(at 2.54 2.54 270)
			(size 1.9939 1.9939)
			(drill 0.249936)
			(layers "*.Cu" "*.Mask")
			(remove_unused_layers no)
			(net "T1_GND")
			(clearance 0.10795)
			(thermal_gap 0.10795)
			(padstack
				(mode front_inner_back)
				(layer "Inner"
					(shape circle)
					(size 0.8001 0.8001)
					(clearance 0.1524)
				)
				(layer "B.Cu"
					(shape circle)
					(size 1.9939 1.9939)
					(clearance 0.10795)
				)
			)
		)
		(pad "4" thru_hole circle
			(at 0 2.54 270)
			(size 1.0033 1.0033)
			(drill 0.249936)
			(layers "*.Cu" "*.Mask")
			(remove_unused_layers no)
			(net "TDR_DIFF_85_NECK_IN1_DN")
			(clearance 0.10795)
			(thermal_gap 0.10795)
			(padstack
				(mode front_inner_back)
				(layer "Inner"
					(shape circle)
					(size 0.8001 0.8001)
					(clearance 0.1524)
				)
				(layer "B.Cu"
					(shape circle)
					(size 1.0033 1.0033)
					(clearance 0.10795)
				)
			)
		)
	)
	(footprint ""
		(layer "F.Cu")
		(at 394.092684 -394.82268 90)
		(property "Reference" "C992"
			(at 0 0 90)
			(layer "F.SilkS")
			(hide yes)
			(effects
				(font
					(size 1.27 1.27)
				)
			)
		)
		(property "Value" ""
			(at 0 0 90)
			(layer "F.Fab")
			(effects
				(font
					(size 1.27 1.27)
				)
			)
		)
		(duplicate_pad_numbers_are_jumpers no)
		(fp_line
			(start 0.7874 -0.4064)
			(end 0.7874 0.4064)
			(stroke
				(width 0.1524)
				(type default)
			)
			(layer "F.SilkS")
		)
		(fp_line
			(start -0.7874 -0.4064)
			(end 0.7874 -0.4064)
			(stroke
				(width 0.1524)
				(type default)
			)
			(layer "F.SilkS")
		)
		(fp_line
			(start 0.7874 0.4064)
			(end -0.7874 0.4064)
			(stroke
				(width 0.1524)
				(type default)
			)
			(layer "F.SilkS")
		)
		(fp_line
			(start -0.7874 0.4064)
			(end -0.7874 -0.4064)
			(stroke
				(width 0.1524)
				(type default)
			)
			(layer "F.SilkS")
		)
		(fp_line
			(start -0.12065 -0.305054)
			(end -0.12065 -0.2794)
			(stroke
				(width 0.1)
				(type default)
			)
			(layer "F.Fab")
		)
		(fp_line
			(start -0.67945 -0.305054)
			(end -0.12065 -0.305054)
			(stroke
				(width 0.1)
				(type default)
			)
			(layer "F.Fab")
		)
		(fp_line
			(start 0.67945 -0.3048)
			(end 0.67945 0.3048)
			(stroke
				(width 0.1)
				(type default)
			)
			(layer "F.Fab")
		)
		(fp_line
			(start 0.12065 -0.3048)
			(end 0.67945 -0.3048)
			(stroke
				(width 0.1)
				(type default)
			)
			(layer "F.Fab")
		)
		(fp_line
			(start 0.12065 -0.2794)
			(end 0.12065 -0.3048)
			(stroke
				(width 0.1)
				(type default)
			)
			(layer "F.Fab")
		)
		(fp_line
			(start -0.12065 -0.2794)
			(end 0.12065 -0.2794)
			(stroke
				(width 0.1)
				(type default)
			)
			(layer "F.Fab")
		)
		(fp_line
			(start 0.120396 0.2794)
			(end -0.12065 0.2794)
			(stroke
				(width 0.1)
				(type default)
			)
			(layer "F.Fab")
		)
		(fp_line
			(start -0.12065 0.2794)
			(end -0.12065 0.3048)
			(stroke
				(width 0.1)
				(type default)
			)
			(layer "F.Fab")
		)
		(fp_line
			(start 0.67945 0.3048)
			(end 0.120396 0.3048)
			(stroke
				(width 0.1)
				(type default)
			)
			(layer "F.Fab")
		)
		(fp_line
			(start 0.120396 0.3048)
			(end 0.120396 0.2794)
			(stroke
				(width 0.1)
				(type default)
			)
			(layer "F.Fab")
		)
		(fp_line
			(start -0.12065 0.3048)
			(end -0.67945 0.3048)
			(stroke
				(width 0.1)
				(type default)
			)
			(layer "F.Fab")
		)
		(fp_line
			(start -0.67945 0.3048)
			(end -0.67945 -0.305054)
			(stroke
				(width 0.1)
				(type default)
			)
			(layer "F.Fab")
		)
		(pad "1" smd circle
			(at -0.40005 0 90)
			(size 0 0)
			(layers "F.Cu" "F.Mask" "F.Paste")
			(net "P1V8_CPU0_RT_1D")
		)
		(pad "2" smd circle
			(at 0.40005 0 90)
			(size 0 0)
			(layers "F.Cu" "F.Mask" "F.Paste")
			(net "GND")
		)
	)
)
